(kicad_pcb
	(version 20260206)
	(generator "pcbnew")
	(generator_version "10.0")
	(general
		(thickness 1.6)
		(legacy_teardrops no)
	)
	(paper "A4")
	(title_block
		(title "01162023_DA0F0TEBIF0_F0T_Expander_BD_F_brd_V02_OCP.brd")
		(comment 1 "Grand Teton / footprints 4731-4737 of 9728")
	)
	(layers
		(0 "F.Cu" signal "TOP")
		(4 "In1.Cu" signal "GND")
		(6 "In2.Cu" signal "VCC")
		(8 "In3.Cu" signal "VCC1")
		(10 "In4.Cu" signal "GND1")
		(12 "In5.Cu" signal "IN1")
		(14 "In6.Cu" signal "GND2")
		(16 "In7.Cu" signal "IN2")
		(18 "In8.Cu" signal "GND3")
		(20 "In9.Cu" signal "IN3")
		(22 "In10.Cu" signal "GND4")
		(24 "In11.Cu" signal "IN4")
		(26 "In12.Cu" signal "GND5")
		(28 "In13.Cu" signal "IN5")
		(30 "In14.Cu" signal "GND6")
		(32 "In15.Cu" signal "IN6")
		(34 "In16.Cu" signal "GND7")
		(2 "B.Cu" signal "BOTTOM")
		(9 "F.Adhes" user "F.Adhesive")
		(11 "B.Adhes" user "B.Adhesive")
		(13 "F.Paste" user "Package Geometry/Pastemask Top")
		(15 "B.Paste" user "Package Geometry/Pastemask Bottom")
		(5 "F.SilkS" user "Ref Des/Silkscreen Top")
		(7 "B.SilkS" user "Ref Des/Silkscreen Bottom")
		(1 "F.Mask" user "Board Geometry/Soldermask Top")
		(3 "B.Mask" user "Board Geometry/Soldermask Bottom")
		(17 "Dwgs.User" user "User.Drawings")
		(19 "Cmts.User" user "User.Comments")
		(21 "Eco1.User" user "User.Eco1")
		(23 "Eco2.User" user "User.Eco2")
		(25 "Edge.Cuts" user "Board Geometry/Outline")
		(27 "Margin" user)
		(31 "F.CrtYd" user "Package Geometry/Place Bound Top")
		(29 "B.CrtYd" user "Package Geometry/Place Bound Bottom")
		(35 "F.Fab" user "Ref Des/Assembly Top")
		(33 "B.Fab" user "Ref Des/Assembly Bottom")
	)
	(footprint ""
		(layer "F.Cu")
		(at 219.202 -192.024)
		(property "Reference" "R1531"
			(at 0 0 0)
			(layer "F.SilkS")
			(hide yes)
			(effects
				(font
					(size 1.27 1.27)
				)
			)
		)
		(property "Value" ""
			(at 0 0 0)
			(layer "F.Fab")
			(effects
				(font
					(size 1.27 1.27)
				)
			)
		)
		(duplicate_pad_numbers_are_jumpers no)
		(fp_line
			(start -0.7874 -0.4064)
			(end 0.7874 -0.4064)
			(stroke
				(width 0.1524)
				(type default)
			)
			(layer "F.SilkS")
		)
		(fp_line
			(start -0.7874 0.4064)
			(end -0.7874 -0.4064)
			(stroke
				(width 0.1524)
				(type default)
			)
			(layer "F.SilkS")
		)
		(fp_line
			(start 0.7874 -0.4064)
			(end 0.7874 0.4064)
			(stroke
				(width 0.1524)
				(type default)
			)
			(layer "F.SilkS")
		)
		(fp_line
			(start 0.7874 0.4064)
			(end -0.7874 0.4064)
			(stroke
				(width 0.1524)
				(type default)
			)
			(layer "F.SilkS")
		)
		(fp_line
			(start -0.67945 -0.305054)
			(end -0.12065 -0.305054)
			(stroke
				(width 0.1)
				(type default)
			)
			(layer "F.Fab")
		)
		(fp_line
			(start -0.67945 0.3048)
			(end -0.67945 -0.305054)
			(stroke
				(width 0.1)
				(type default)
			)
			(layer "F.Fab")
		)
		(fp_line
			(start -0.12065 -0.305054)
			(end -0.12065 -0.2794)
			(stroke
				(width 0.1)
				(type default)
			)
			(layer "F.Fab")
		)
		(fp_line
			(start -0.12065 -0.2794)
			(end 0.12065 -0.2794)
			(stroke
				(width 0.1)
				(type default)
			)
			(layer "F.Fab")
		)
		(fp_line
			(start -0.12065 0.2794)
			(end -0.12065 0.3048)
			(stroke
				(width 0.1)
				(type default)
			)
			(layer "F.Fab")
		)
		(fp_line
			(start -0.12065 0.3048)
			(end -0.67945 0.3048)
			(stroke
				(width 0.1)
				(type default)
			)
			(layer "F.Fab")
		)
		(fp_line
			(start 0.120396 0.2794)
			(end -0.12065 0.2794)
			(stroke
				(width 0.1)
				(type default)
			)
			(layer "F.Fab")
		)
		(fp_line
			(start 0.120396 0.3048)
			(end 0.120396 0.2794)
			(stroke
				(width 0.1)
				(type default)
			)
			(layer "F.Fab")
		)
		(fp_line
			(start 0.12065 -0.3048)
			(end 0.67945 -0.3048)
			(stroke
				(width 0.1)
				(type default)
			)
			(layer "F.Fab")
		)
		(fp_line
			(start 0.12065 -0.2794)
			(end 0.12065 -0.3048)
			(stroke
				(width 0.1)
				(type default)
			)
			(layer "F.Fab")
		)
		(fp_line
			(start 0.67945 -0.3048)
			(end 0.67945 0.3048)
			(stroke
				(width 0.1)
				(type default)
			)
			(layer "F.Fab")
		)
		(fp_line
			(start 0.67945 0.3048)
			(end 0.120396 0.3048)
			(stroke
				(width 0.1)
				(type default)
			)
			(layer "F.Fab")
		)
		(pad "1" smd circle
			(at -0.40005 0)
			(size 0 0)
			(layers "F.Cu" "F.Mask" "F.Paste")
			(net "SMB_NIC7_LS_EN")
		)
		(pad "2" smd circle
			(at 0.40005 0)
			(size 0 0)
			(layers "F.Cu" "F.Mask" "F.Paste")
			(net "P3V3_NIC7")
		)
	)
	(footprint ""
		(layer "F.Cu")
		(at 228.79304 -90.009726)
		(property "Reference" "R1012"
			(at 0 0 0)
			(layer "F.SilkS")
			(hide yes)
			(effects
				(font
					(size 1.27 1.27)
				)
			)
		)
		(property "Value" ""
			(at 0 0 0)
			(layer "F.Fab")
			(effects
				(font
					(size 1.27 1.27)
				)
			)
		)
		(duplicate_pad_numbers_are_jumpers no)
		(fp_line
			(start -0.7874 -0.4064)
			(end 0.7874 -0.4064)
			(stroke
				(width 0.1524)
				(type default)
			)
			(layer "F.SilkS")
		)
		(fp_line
			(start -0.7874 0.4064)
			(end -0.7874 -0.4064)
			(stroke
				(width 0.1524)
				(type default)
			)
			(layer "F.SilkS")
		)
		(fp_line
			(start 0.7874 -0.4064)
			(end 0.7874 0.4064)
			(stroke
				(width 0.1524)
				(type default)
			)
			(layer "F.SilkS")
		)
		(fp_line
			(start 0.7874 0.4064)
			(end -0.7874 0.4064)
			(stroke
				(width 0.1524)
				(type default)
			)
			(layer "F.SilkS")
		)
		(fp_line
			(start -0.67945 -0.305054)
			(end -0.12065 -0.305054)
			(stroke
				(width 0.1)
				(type default)
			)
			(layer "F.Fab")
		)
		(fp_line
			(start -0.67945 0.3048)
			(end -0.67945 -0.305054)
			(stroke
				(width 0.1)
				(type default)
			)
			(layer "F.Fab")
		)
		(fp_line
			(start -0.12065 -0.305054)
			(end -0.12065 -0.2794)
			(stroke
				(width 0.1)
				(type default)
			)
			(layer "F.Fab")
		)
		(fp_line
			(start -0.12065 -0.2794)
			(end 0.12065 -0.2794)
			(stroke
				(width 0.1)
				(type default)
			)
			(layer "F.Fab")
		)
		(fp_line
			(start -0.12065 0.2794)
			(end -0.12065 0.3048)
			(stroke
				(width 0.1)
				(type default)
			)
			(layer "F.Fab")
		)
		(fp_line
			(start -0.12065 0.3048)
			(end -0.67945 0.3048)
			(stroke
				(width 0.1)
				(type default)
			)
			(layer "F.Fab")
		)
		(fp_line
			(start 0.120396 0.2794)
			(end -0.12065 0.2794)
			(stroke
				(width 0.1)
				(type default)
			)
			(layer "F.Fab")
		)
		(fp_line
			(start 0.120396 0.3048)
			(end 0.120396 0.2794)
			(stroke
				(width 0.1)
				(type default)
			)
			(layer "F.Fab")
		)
		(fp_line
			(start 0.12065 -0.3048)
			(end 0.67945 -0.3048)
			(stroke
				(width 0.1)
				(type default)
			)
			(layer "F.Fab")
		)
		(fp_line
			(start 0.12065 -0.2794)
			(end 0.12065 -0.3048)
			(stroke
				(width 0.1)
				(type default)
			)
			(layer "F.Fab")
		)
		(fp_line
			(start 0.67945 -0.3048)
			(end 0.67945 0.3048)
			(stroke
				(width 0.1)
				(type default)
			)
			(layer "F.Fab")
		)
		(fp_line
			(start 0.67945 0.3048)
			(end 0.120396 0.3048)
			(stroke
				(width 0.1)
				(type default)
			)
			(layer "F.Fab")
		)
		(pad "1" smd circle
			(at -0.40005 0)
			(size 0 0)
			(layers "F.Cu" "F.Mask" "F.Paste")
			(net "P3V3_AUX")
		)
		(pad "2" smd circle
			(at 0.40005 0)
			(size 0 0)
			(layers "F.Cu" "F.Mask" "F.Paste")
			(net "PEX_USB_HUB_OVCUR1")
		)
	)
	(footprint ""
		(layer "F.Cu")
		(at 274.089622 -350.098614 90)
		(property "Reference" "C607"
			(at 0 0 90)
			(layer "F.SilkS")
			(hide yes)
			(effects
				(font
					(size 1.27 1.27)
				)
			)
		)
		(property "Value" ""
			(at 0 0 90)
			(layer "F.Fab")
			(effects
				(font
					(size 1.27 1.27)
				)
			)
		)
		(duplicate_pad_numbers_are_jumpers no)
		(fp_line
			(start 0.299974 -0.150114)
			(end 0.299974 0.150114)
			(stroke
				(width 0.1)
				(type default)
			)
			(layer "F.Fab")
		)
		(fp_line
			(start -0.299974 -0.150114)
			(end 0.299974 -0.150114)
			(stroke
				(width 0.1)
				(type default)
			)
			(layer "F.Fab")
		)
		(fp_line
			(start 0.299974 0.150114)
			(end -0.299974 0.150114)
			(stroke
				(width 0.1)
				(type default)
			)
			(layer "F.Fab")
		)
		(fp_line
			(start -0.299974 0.150114)
			(end -0.299974 -0.150114)
			(stroke
				(width 0.1)
				(type default)
			)
			(layer "F.Fab")
		)
		(pad "1" smd rect
			(at -0.2667 0 90)
			(size 0.3048 0.381)
			(layers "F.Cu" "F.Mask" "F.Paste")
			(net "P5E_PEX2_STN7_TX_DP<115>")
		)
		(pad "2" smd rect
			(at 0.2667 0 90)
			(size 0.3048 0.381)
			(layers "F.Cu" "F.Mask" "F.Paste")
			(net "P5E_PEX2_STN7_TX_C_DP<115>")
		)
	)
	(footprint ""
		(layer "F.Cu")
		(at 458.155548 -373.71782 -90)
		(property "Reference" "R6683"
			(at 0 0 270)
			(layer "F.SilkS")
			(hide yes)
			(effects
				(font
					(size 1.27 1.27)
				)
			)
		)
		(property "Value" ""
			(at 0 0 270)
			(layer "F.Fab")
			(effects
				(font
					(size 1.27 1.27)
				)
			)
		)
		(duplicate_pad_numbers_are_jumpers no)
		(fp_line
			(start -0.7874 0.4064)
			(end -0.7874 -0.4064)
			(stroke
				(width 0.1524)
				(type default)
			)
			(layer "F.SilkS")
		)
		(fp_line
			(start 0.7874 0.4064)
			(end -0.7874 0.4064)
			(stroke
				(width 0.1524)
				(type default)
			)
			(layer "F.SilkS")
		)
		(fp_line
			(start -0.7874 -0.4064)
			(end 0.7874 -0.4064)
			(stroke
				(width 0.1524)
				(type default)
			)
			(layer "F.SilkS")
		)
		(fp_line
			(start 0.7874 -0.4064)
			(end 0.7874 0.4064)
			(stroke
				(width 0.1524)
				(type default)
			)
			(layer "F.SilkS")
		)
		(fp_line
			(start -0.67945 0.3048)
			(end -0.67945 -0.305054)
			(stroke
				(width 0.1)
				(type default)
			)
			(layer "F.Fab")
		)
		(fp_line
			(start -0.12065 0.3048)
			(end -0.67945 0.3048)
			(stroke
				(width 0.1)
				(type default)
			)
			(layer "F.Fab")
		)
		(fp_line
			(start 0.120396 0.3048)
			(end 0.120396 0.2794)
			(stroke
				(width 0.1)
				(type default)
			)
			(layer "F.Fab")
		)
		(fp_line
			(start 0.67945 0.3048)
			(end 0.120396 0.3048)
			(stroke
				(width 0.1)
				(type default)
			)
			(layer "F.Fab")
		)
		(fp_line
			(start -0.12065 0.2794)
			(end -0.12065 0.3048)
			(stroke
				(width 0.1)
				(type default)
			)
			(layer "F.Fab")
		)
		(fp_line
			(start 0.120396 0.2794)
			(end -0.12065 0.2794)
			(stroke
				(width 0.1)
				(type default)
			)
			(layer "F.Fab")
		)
		(fp_line
			(start -0.12065 -0.2794)
			(end 0.12065 -0.2794)
			(stroke
				(width 0.1)
				(type default)
			)
			(layer "F.Fab")
		)
		(fp_line
			(start 0.12065 -0.2794)
			(end 0.12065 -0.3048)
			(stroke
				(width 0.1)
				(type default)
			)
			(layer "F.Fab")
		)
		(fp_line
			(start 0.12065 -0.3048)
			(end 0.67945 -0.3048)
			(stroke
				(width 0.1)
				(type default)
			)
			(layer "F.Fab")
		)
		(fp_line
			(start 0.67945 -0.3048)
			(end 0.67945 0.3048)
			(stroke
				(width 0.1)
				(type default)
			)
			(layer "F.Fab")
		)
		(fp_line
			(start -0.67945 -0.305054)
			(end -0.12065 -0.305054)
			(stroke
				(width 0.1)
				(type default)
			)
			(layer "F.Fab")
		)
		(fp_line
			(start -0.12065 -0.305054)
			(end -0.12065 -0.2794)
			(stroke
				(width 0.1)
				(type default)
			)
			(layer "F.Fab")
		)
		(pad "1" smd circle
			(at -0.40005 0 270)
			(size 0 0)
			(layers "F.Cu" "F.Mask" "F.Paste")
			(net "GPU_3V3IO_RSVD3_ISO")
		)
		(pad "2" smd circle
			(at 0.40005 0 270)
			(size 0 0)
			(layers "F.Cu" "F.Mask" "F.Paste")
			(net "P3V3_AUX")
		)
	)
	(footprint ""
		(layer "F.Cu")
		(at 228.915722 -308.162452 90)
		(property "Reference" "PC242"
			(at 0 0 90)
			(layer "F.SilkS")
			(hide yes)
			(effects
				(font
					(size 1.27 1.27)
				)
			)
		)
		(property "Value" ""
			(at 0 0 90)
			(layer "F.Fab")
			(effects
				(font
					(size 1.27 1.27)
				)
			)
		)
		(duplicate_pad_numbers_are_jumpers no)
		(fp_line
			(start 0.7874 -0.4064)
			(end 0.7874 0.4064)
			(stroke
				(width 0.1524)
				(type default)
			)
			(layer "F.SilkS")
		)
		(fp_line
			(start -0.7874 -0.4064)
			(end 0.7874 -0.4064)
			(stroke
				(width 0.1524)
				(type default)
			)
			(layer "F.SilkS")
		)
		(fp_line
			(start 0.7874 0.4064)
			(end -0.7874 0.4064)
			(stroke
				(width 0.1524)
				(type default)
			)
			(layer "F.SilkS")
		)
		(fp_line
			(start -0.7874 0.4064)
			(end -0.7874 -0.4064)
			(stroke
				(width 0.1524)
				(type default)
			)
			(layer "F.SilkS")
		)
		(fp_line
			(start -0.12065 -0.305054)
			(end -0.12065 -0.2794)
			(stroke
				(width 0.1)
				(type default)
			)
			(layer "F.Fab")
		)
		(fp_line
			(start -0.67945 -0.305054)
			(end -0.12065 -0.305054)
			(stroke
				(width 0.1)
				(type default)
			)
			(layer "F.Fab")
		)
		(fp_line
			(start 0.67945 -0.3048)
			(end 0.67945 0.3048)
			(stroke
				(width 0.1)
				(type default)
			)
			(layer "F.Fab")
		)
		(fp_line
			(start 0.12065 -0.3048)
			(end 0.67945 -0.3048)
			(stroke
				(width 0.1)
				(type default)
			)
			(layer "F.Fab")
		)
		(fp_line
			(start 0.12065 -0.2794)
			(end 0.12065 -0.3048)
			(stroke
				(width 0.1)
				(type default)
			)
			(layer "F.Fab")
		)
		(fp_line
			(start -0.12065 -0.2794)
			(end 0.12065 -0.2794)
			(stroke
				(width 0.1)
				(type default)
			)
			(layer "F.Fab")
		)
		(fp_line
			(start 0.120396 0.2794)
			(end -0.12065 0.2794)
			(stroke
				(width 0.1)
				(type default)
			)
			(layer "F.Fab")
		)
		(fp_line
			(start -0.12065 0.2794)
			(end -0.12065 0.3048)
			(stroke
				(width 0.1)
				(type default)
			)
			(layer "F.Fab")
		)
		(fp_line
			(start 0.67945 0.3048)
			(end 0.120396 0.3048)
			(stroke
				(width 0.1)
				(type default)
			)
			(layer "F.Fab")
		)
		(fp_line
			(start 0.120396 0.3048)
			(end 0.120396 0.2794)
			(stroke
				(width 0.1)
				(type default)
			)
			(layer "F.Fab")
		)
		(fp_line
			(start -0.12065 0.3048)
			(end -0.67945 0.3048)
			(stroke
				(width 0.1)
				(type default)
			)
			(layer "F.Fab")
		)
		(fp_line
			(start -0.67945 0.3048)
			(end -0.67945 -0.305054)
			(stroke
				(width 0.1)
				(type default)
			)
			(layer "F.Fab")
		)
		(pad "1" smd circle
			(at -0.40005 0 90)
			(size 0 0)
			(layers "F.Cu" "F.Mask" "F.Paste")
			(net "P1V25_PEX1_REF")
		)
		(pad "2" smd circle
			(at 0.40005 0 90)
			(size 0 0)
			(layers "F.Cu" "F.Mask" "F.Paste")
			(net "SH_P1V25_PEX1_FB_N")
		)
	)
	(footprint ""
		(layer "F.Cu")
		(at 38.782752 -140.85697)
		(property "Reference" "R34"
			(at 0 0 0)
			(layer "F.SilkS")
			(hide yes)
			(effects
				(font
					(size 1.27 1.27)
				)
			)
		)
		(property "Value" ""
			(at 0 0 0)
			(layer "F.Fab")
			(effects
				(font
					(size 1.27 1.27)
				)
			)
		)
		(duplicate_pad_numbers_are_jumpers no)
		(fp_line
			(start -0.7874 -0.4064)
			(end 0.7874 -0.4064)
			(stroke
				(width 0.1524)
				(type default)
			)
			(layer "F.SilkS")
		)
		(fp_line
			(start -0.7874 0.4064)
			(end -0.7874 -0.4064)
			(stroke
				(width 0.1524)
				(type default)
			)
			(layer "F.SilkS")
		)
		(fp_line
			(start 0.7874 -0.4064)
			(end 0.7874 0.4064)
			(stroke
				(width 0.1524)
				(type default)
			)
			(layer "F.SilkS")
		)
		(fp_line
			(start 0.7874 0.4064)
			(end -0.7874 0.4064)
			(stroke
				(width 0.1524)
				(type default)
			)
			(layer "F.SilkS")
		)
		(fp_line
			(start -0.67945 -0.305054)
			(end -0.12065 -0.305054)
			(stroke
				(width 0.1)
				(type default)
			)
			(layer "F.Fab")
		)
		(fp_line
			(start -0.67945 0.3048)
			(end -0.67945 -0.305054)
			(stroke
				(width 0.1)
				(type default)
			)
			(layer "F.Fab")
		)
		(fp_line
			(start -0.12065 -0.305054)
			(end -0.12065 -0.2794)
			(stroke
				(width 0.1)
				(type default)
			)
			(layer "F.Fab")
		)
		(fp_line
			(start -0.12065 -0.2794)
			(end 0.12065 -0.2794)
			(stroke
				(width 0.1)
				(type default)
			)
			(layer "F.Fab")
		)
		(fp_line
			(start -0.12065 0.2794)
			(end -0.12065 0.3048)
			(stroke
				(width 0.1)
				(type default)
			)
			(layer "F.Fab")
		)
		(fp_line
			(start -0.12065 0.3048)
			(end -0.67945 0.3048)
			(stroke
				(width 0.1)
				(type default)
			)
			(layer "F.Fab")
		)
		(fp_line
			(start 0.120396 0.2794)
			(end -0.12065 0.2794)
			(stroke
				(width 0.1)
				(type default)
			)
			(layer "F.Fab")
		)
		(fp_line
			(start 0.120396 0.3048)
			(end 0.120396 0.2794)
			(stroke
				(width 0.1)
				(type default)
			)
			(layer "F.Fab")
		)
		(fp_line
			(start 0.12065 -0.3048)
			(end 0.67945 -0.3048)
			(stroke
				(width 0.1)
				(type default)
			)
			(layer "F.Fab")
		)
		(fp_line
			(start 0.12065 -0.2794)
			(end 0.12065 -0.3048)
			(stroke
				(width 0.1)
				(type default)
			)
			(layer "F.Fab")
		)
		(fp_line
			(start 0.67945 -0.3048)
			(end 0.67945 0.3048)
			(stroke
				(width 0.1)
				(type default)
			)
			(layer "F.Fab")
		)
		(fp_line
			(start 0.67945 0.3048)
			(end 0.120396 0.3048)
			(stroke
				(width 0.1)
				(type default)
			)
			(layer "F.Fab")
		)
		(pad "1" smd circle
			(at -0.40005 0)
			(size 0 0)
			(layers "F.Cu" "F.Mask" "F.Paste")
			(net "NIC0_BIF2_N")
		)
		(pad "2" smd circle
			(at 0.40005 0)
			(size 0 0)
			(layers "F.Cu" "F.Mask" "F.Paste")
			(net "GND")
		)
	)
	(footprint ""
		(layer "F.Cu")
		(at 241.567208 -305.338988)
		(property "Reference" "PC248"
			(at 0 0 0)
			(layer "F.SilkS")
			(hide yes)
			(effects
				(font
					(size 1.27 1.27)
				)
			)
		)
		(property "Value" ""
			(at 0 0 0)
			(layer "F.Fab")
			(effects
				(font
					(size 1.27 1.27)
				)
			)
		)
		(duplicate_pad_numbers_are_jumpers no)
		(fp_line
			(start -0.7874 -0.4064)
			(end 0.7874 -0.4064)
			(stroke
				(width 0.1524)
				(type default)
			)
			(layer "F.SilkS")
		)
		(fp_line
			(start -0.7874 0.4064)
			(end -0.7874 -0.4064)
			(stroke
				(width 0.1524)
				(type default)
			)
			(layer "F.SilkS")
		)
		(fp_line
			(start 0.7874 -0.4064)
			(end 0.7874 0.4064)
			(stroke
				(width 0.1524)
				(type default)
			)
			(layer "F.SilkS")
		)
		(fp_line
			(start 0.7874 0.4064)
			(end -0.7874 0.4064)
			(stroke
				(width 0.1524)
				(type default)
			)
			(layer "F.SilkS")
		)
		(fp_line
			(start -0.67945 -0.305054)
			(end -0.12065 -0.305054)
			(stroke
				(width 0.1)
				(type default)
			)
			(layer "F.Fab")
		)
		(fp_line
			(start -0.67945 0.3048)
			(end -0.67945 -0.305054)
			(stroke
				(width 0.1)
				(type default)
			)
			(layer "F.Fab")
		)
		(fp_line
			(start -0.12065 -0.305054)
			(end -0.12065 -0.2794)
			(stroke
				(width 0.1)
				(type default)
			)
			(layer "F.Fab")
		)
		(fp_line
			(start -0.12065 -0.2794)
			(end 0.12065 -0.2794)
			(stroke
				(width 0.1)
				(type default)
			)
			(layer "F.Fab")
		)
		(fp_line
			(start -0.12065 0.2794)
			(end -0.12065 0.3048)
			(stroke
				(width 0.1)
				(type default)
			)
			(layer "F.Fab")
		)
		(fp_line
			(start -0.12065 0.3048)
			(end -0.67945 0.3048)
			(stroke
				(width 0.1)
				(type default)
			)
			(layer "F.Fab")
		)
		(fp_line
			(start 0.120396 0.2794)
			(end -0.12065 0.2794)
			(stroke
				(width 0.1)
				(type default)
			)
			(layer "F.Fab")
		)
		(fp_line
			(start 0.120396 0.3048)
			(end 0.120396 0.2794)
			(stroke
				(width 0.1)
				(type default)
			)
			(layer "F.Fab")
		)
		(fp_line
			(start 0.12065 -0.3048)
			(end 0.67945 -0.3048)
			(stroke
				(width 0.1)
				(type default)
			)
			(layer "F.Fab")
		)
		(fp_line
			(start 0.12065 -0.2794)
			(end 0.12065 -0.3048)
			(stroke
				(width 0.1)
				(type default)
			)
			(layer "F.Fab")
		)
		(fp_line
			(start 0.67945 -0.3048)
			(end 0.67945 0.3048)
			(stroke
				(width 0.1)
				(type default)
			)
			(layer "F.Fab")
		)
		(fp_line
			(start 0.67945 0.3048)
			(end 0.120396 0.3048)
			(stroke
				(width 0.1)
				(type default)
			)
			(layer "F.Fab")
		)
		(pad "1" smd circle
			(at -0.40005 0)
			(size 0 0)
			(layers "F.Cu" "F.Mask" "F.Paste")
			(net "SW_P12V_P1V25_PEX2_FLT")
		)
		(pad "2" smd circle
			(at 0.40005 0)
			(size 0 0)
			(layers "F.Cu" "F.Mask" "F.Paste")
			(net "GND")
		)
	)
)
